# S9S_MB_2U (Grand Teton) — schematic netlist excerpt (pin names and nets, part order shuffled) for the footprints in the layout excerpt that follows; sources: Cadence DE-HDL packaged netlist, KiCad conversion of 03242023_DA0F0TMBIJ0_F0T_Motherboard_J_brd_V01_OCP.brd

C2246  Q_CAP  1UF 25V 10% X6S  pkg C0402  page 225 : A = P3V3_AUX ; B = GND
R315  Q_RES  33.2 1% CHIP  pkg 0402LF  page 118 : A = PWRGD_CPUPWRGD_GTL ; B = PWRGD_CPUPWRGD_LVC1_R

(kicad_pcb
	(version 20260206)
	(generator "pcbnew")
	(generator_version "10.0")
	(general
		(thickness 1.6)
		(legacy_teardrops no)
	)
	(paper "A4")
	(title_block
		(title "03242023_DA0F0TMBIJ0_F0T_Motherboard_J_brd_V01_OCP.brd")
		(comment 1 "Grand Teton / footprints 1992-1993 of 6105")
	)
	(layers
		(0 "F.Cu" signal "TOP")
		(4 "In1.Cu" signal "GND")
		(6 "In2.Cu" signal "IN1")
		(8 "In3.Cu" signal "GND1")
		(10 "In4.Cu" signal "IN2")
		(12 "In5.Cu" signal "GND2")
		(14 "In6.Cu" signal "IN3")
		(16 "In7.Cu" signal "GND3")
		(18 "In8.Cu" signal "VCC")
		(20 "In9.Cu" signal "VCC1")
		(22 "In10.Cu" signal "GND4")
		(24 "In11.Cu" signal "IN4")
		(26 "In12.Cu" signal "GND5")
		(28 "In13.Cu" signal "IN5")
		(30 "In14.Cu" signal "GND6")
		(32 "In15.Cu" signal "IN6")
		(34 "In16.Cu" signal "GND7")
		(2 "B.Cu" signal "BOTTOM")
		(9 "F.Adhes" user "F.Adhesive")
		(11 "B.Adhes" user "B.Adhesive")
		(13 "F.Paste" user "Package Geometry/Pastemask Top")
		(15 "B.Paste" user "Package Geometry/Pastemask Bottom")
		(5 "F.SilkS" user "Ref Des/Silkscreen Top")
		(7 "B.SilkS" user "Ref Des/Silkscreen Bottom")
		(1 "F.Mask" user "Board Geometry/Soldermask Top")
		(3 "B.Mask" user "Board Geometry/Soldermask Bottom")
		(17 "Dwgs.User" user "User.Drawings")
		(19 "Cmts.User" user "User.Comments")
		(21 "Eco1.User" user "User.Eco1")
		(23 "Eco2.User" user "User.Eco2")
		(25 "Edge.Cuts" user "Board Geometry/Outline")
		(27 "Margin" user)
		(31 "F.CrtYd" user "Package Geometry/Place Bound Top")
		(29 "B.CrtYd" user "Package Geometry/Place Bound Bottom")
		(35 "F.Fab" user "Ref Des/Assembly Top")
		(33 "B.Fab" user "Ref Des/Assembly Bottom")
	)
	(footprint ""
		(layer "F.Cu")
		(at 117.581934 -108.331762 -90)
		(property "Reference" "C2246"
			(at 0 0 270)
			(layer "F.SilkS")
			(hide yes)
			(effects
				(font
					(size 1.27 1.27)
				)
			)
		)
		(property "Value" ""
			(at 0 0 270)
			(layer "F.Fab")
			(effects
				(font
					(size 1.27 1.27)
				)
			)
		)
		(duplicate_pad_numbers_are_jumpers no)
		(fp_line
			(start -0.7874 0.4064)
			(end -0.7874 -0.4064)
			(stroke
				(width 0.1524)
				(type default)
			)
			(layer "F.SilkS")
		)
		(fp_line
			(start 0.7874 0.4064)
			(end -0.7874 0.4064)
			(stroke
				(width 0.1524)
				(type default)
			)
			(layer "F.SilkS")
		)
		(fp_line
			(start -0.7874 -0.4064)
			(end 0.7874 -0.4064)
			(stroke
				(width 0.1524)
				(type default)
			)
			(layer "F.SilkS")
		)
		(fp_line
			(start 0.7874 -0.4064)
			(end 0.7874 0.4064)
			(stroke
				(width 0.1524)
				(type default)
			)
			(layer "F.SilkS")
		)
		(fp_line
			(start -0.67945 0.3048)
			(end -0.67945 -0.305054)
			(stroke
				(width 0.1)
				(type default)
			)
			(layer "F.Fab")
		)
		(fp_line
			(start -0.12065 0.3048)
			(end -0.67945 0.3048)
			(stroke
				(width 0.1)
				(type default)
			)
			(layer "F.Fab")
		)
		(fp_line
			(start 0.120396 0.3048)
			(end 0.120396 0.2794)
			(stroke
				(width 0.1)
				(type default)
			)
			(layer "F.Fab")
		)
		(fp_line
			(start 0.67945 0.3048)
			(end 0.120396 0.3048)
			(stroke
				(width 0.1)
				(type default)
			)
			(layer "F.Fab")
		)
		(fp_line
			(start -0.12065 0.2794)
			(end -0.12065 0.3048)
			(stroke
				(width 0.1)
				(type default)
			)
			(layer "F.Fab")
		)
		(fp_line
			(start 0.120396 0.2794)
			(end -0.12065 0.2794)
			(stroke
				(width 0.1)
				(type default)
			)
			(layer "F.Fab")
		)
		(fp_line
			(start -0.12065 -0.2794)
			(end 0.12065 -0.2794)
			(stroke
				(width 0.1)
				(type default)
			)
			(layer "F.Fab")
		)
		(fp_line
			(start 0.12065 -0.2794)
			(end 0.12065 -0.3048)
			(stroke
				(width 0.1)
				(type default)
			)
			(layer "F.Fab")
		)
		(fp_line
			(start 0.12065 -0.3048)
			(end 0.67945 -0.3048)
			(stroke
				(width 0.1)
				(type default)
			)
			(layer "F.Fab")
		)
		(fp_line
			(start 0.67945 -0.3048)
			(end 0.67945 0.3048)
			(stroke
				(width 0.1)
				(type default)
			)
			(layer "F.Fab")
		)
		(fp_line
			(start -0.67945 -0.305054)
			(end -0.12065 -0.305054)
			(stroke
				(width 0.1)
				(type default)
			)
			(layer "F.Fab")
		)
		(fp_line
			(start -0.12065 -0.305054)
			(end -0.12065 -0.2794)
			(stroke
				(width 0.1)
				(type default)
			)
			(layer "F.Fab")
		)
		(pad "1" smd circle
			(at -0.40005 0 270)
			(size 0 0)
			(layers "F.Cu" "F.Mask" "F.Paste")
			(net "P3V3_AUX")
		)
		(pad "2" smd circle
			(at 0.40005 0 270)
			(size 0 0)
			(layers "F.Cu" "F.Mask" "F.Paste")
			(net "GND")
		)
	)
	(footprint ""
		(layer "F.Cu")
		(at 310.007 -53.050948 -90)
		(property "Reference" "R315"
			(at 0 0 270)
			(layer "F.SilkS")
			(hide yes)
			(effects
				(font
					(size 1.27 1.27)
				)
			)
		)
		(property "Value" ""
			(at 0 0 270)
			(layer "F.Fab")
			(effects
				(font
					(size 1.27 1.27)
				)
			)
		)
		(duplicate_pad_numbers_are_jumpers no)
		(fp_line
			(start -0.7874 0.4064)
			(end -0.7874 -0.4064)
			(stroke
				(width 0.1524)
				(type default)
			)
			(layer "F.SilkS")
		)
		(fp_line
			(start 0.7874 0.4064)
			(end -0.7874 0.4064)
			(stroke
				(width 0.1524)
				(type default)
			)
			(layer "F.SilkS")
		)
		(fp_line
			(start -0.7874 -0.4064)
			(end 0.7874 -0.4064)
			(stroke
				(width 0.1524)
				(type default)
			)
			(layer "F.SilkS")
		)
		(fp_line
			(start 0.7874 -0.4064)
			(end 0.7874 0.4064)
			(stroke
				(width 0.1524)
				(type default)
			)
			(layer "F.SilkS")
		)
		(fp_line
			(start -0.67945 0.3048)
			(end -0.67945 -0.305054)
			(stroke
				(width 0.1)
				(type default)
			)
			(layer "F.Fab")
		)
		(fp_line
			(start -0.12065 0.3048)
			(end -0.67945 0.3048)
			(stroke
				(width 0.1)
				(type default)
			)
			(layer "F.Fab")
		)
		(fp_line
			(start 0.120396 0.3048)
			(end 0.120396 0.2794)
			(stroke
				(width 0.1)
				(type default)
			)
			(layer "F.Fab")
		)
		(fp_line
			(start 0.67945 0.3048)
			(end 0.120396 0.3048)
			(stroke
				(width 0.1)
				(type default)
			)
			(layer "F.Fab")
		)
		(fp_line
			(start -0.12065 0.2794)
			(end -0.12065 0.3048)
			(stroke
				(width 0.1)
				(type default)
			)
			(layer "F.Fab")
		)
		(fp_line
			(start 0.120396 0.2794)
			(end -0.12065 0.2794)
			(stroke
				(width 0.1)
				(type default)
			)
			(layer "F.Fab")
		)
		(fp_line
			(start -0.12065 -0.2794)
			(end 0.12065 -0.2794)
			(stroke
				(width 0.1)
				(type default)
			)
			(layer "F.Fab")
		)
		(fp_line
			(start 0.12065 -0.2794)
			(end 0.12065 -0.3048)
			(stroke
				(width 0.1)
				(type default)
			)
			(layer "F.Fab")
		)
		(fp_line
			(start 0.12065 -0.3048)
			(end 0.67945 -0.3048)
			(stroke
				(width 0.1)
				(type default)
			)
			(layer "F.Fab")
		)
		(fp_line
			(start 0.67945 -0.3048)
			(end 0.67945 0.3048)
			(stroke
				(width 0.1)
				(type default)
			)
			(layer "F.Fab")
		)
		(fp_line
			(start -0.67945 -0.305054)
			(end -0.12065 -0.305054)
			(stroke
				(width 0.1)
				(type default)
			)
			(layer "F.Fab")
		)
		(fp_line
			(start -0.12065 -0.305054)
			(end -0.12065 -0.2794)
			(stroke
				(width 0.1)
				(type default)
			)
			(layer "F.Fab")
		)
		(pad "1" smd circle
			(at -0.40005 0 270)
			(size 0 0)
			(layers "F.Cu" "F.Mask" "F.Paste")
			(net "PWRGD_CPUPWRGD_GTL")
		)
		(pad "2" smd circle
			(at 0.40005 0 270)
			(size 0 0)
			(layers "F.Cu" "F.Mask" "F.Paste")
			(net "PWRGD_CPUPWRGD_LVC1_R")
		)
	)
)
